(kicad_pcb
	(version 20260206)
	(generator "pcbnew")
	(generator_version "10.0")
	(general
		(thickness 1.6)
		(legacy_teardrops no)
	)
	(paper "A4")
	(title_block
		(title "fcb — 12433-1M.1206WZS1330.brd")
		(comment 1 "Open Vault / Knox (Wiwynn) / footprints 24-28 of 495")
	)
	(layers
		(0 "F.Cu" signal "TOP")
		(4 "In1.Cu" signal "L2GND")
		(6 "In2.Cu" signal "L3VCC")
		(2 "B.Cu" signal "BOTTOM")
		(9 "F.Adhes" user "F.Adhesive")
		(11 "B.Adhes" user "B.Adhesive")
		(13 "F.Paste" user "Package Geometry/Pastemask Top")
		(15 "B.Paste" user "Package Geometry/Pastemask Bottom")
		(5 "F.SilkS" user "Ref Des/Silkscreen Top")
		(7 "B.SilkS" user "Ref Des/Silkscreen Bottom")
		(1 "F.Mask" user "Board Geometry/Soldermask Top")
		(3 "B.Mask" user "Board Geometry/Soldermask Bottom")
		(17 "Dwgs.User" user "User.Drawings")
		(19 "Cmts.User" user "User.Comments")
		(21 "Eco1.User" user "User.Eco1")
		(23 "Eco2.User" user "User.Eco2")
		(25 "Edge.Cuts" user "Board Geometry/Outline")
		(27 "Margin" user)
		(31 "F.CrtYd" user "Package Geometry/Place Bound Top")
		(29 "B.CrtYd" user "Package Geometry/Place Bound Bottom")
		(35 "F.Fab" user "Ref Des/Assembly Top")
		(33 "B.Fab" user "Ref Des/Assembly Bottom")
	)
	(footprint ""
		(layer "F.Cu")
		(at 41.8084 -155.0162 180)
		(property "Reference" "C4"
			(at 0 0 180)
			(layer "F.SilkS")
			(hide yes)
			(effects
				(font
					(size 1.27 1.27)
				)
			)
		)
		(property "Value" "SCD1U16V2KX-3GP"
			(at 1.1811 -2.7051 180)
			(unlocked yes)
			(layer "F.Fab")
			(hide yes)
			(effects
				(font
					(size 1.016 1.016)
					(thickness 0.1524)
				)
			)
		)
		(property "Device Type" "C402H22"
			(at 1.1811 -4.2291 180)
			(unlocked yes)
			(layer "F.Fab")
			(hide yes)
			(effects
				(font
					(size 1.016 1.016)
					(thickness 0.1524)
				)
			)
		)
		(duplicate_pad_numbers_are_jumpers no)
		(fp_rect
			(start -0.4318 0.9525)
			(end 0.4318 -0.9525)
			(stroke
				(width 0)
				(type default)
			)
			(fill no)
			(layer "F.CrtYd")
		)
		(fp_rect
			(start -0.4318 0.9525)
			(end 0.4318 -0.9525)
			(stroke
				(width 0)
				(type default)
			)
			(fill no)
			(layer "F.Fab")
		)
		(pad "1" smd custom
			(at 0 -0.4445 180)
			(size 0.1524 0.1524)
			(layers "F.Cu" "F.Mask" "F.Paste")
			(net "NCT7904_3VSB")
			(options
				(clearance outline)
				(anchor circle)
			)
			(primitives
				(gr_poly
					(pts
						(arc
							(start 0.3048 -0.2032)
							(mid 0.275042 -0.275042)
							(end 0.2032 -0.3048)
						)
						(arc
							(start -0.2032 -0.3048)
							(mid -0.275042 -0.275042)
							(end -0.3048 -0.2032)
						)
						(arc
							(start -0.3048 0.2032)
							(mid -0.275042 0.275042)
							(end -0.2032 0.3048)
						)
						(arc
							(start 0.2032 0.3048)
							(mid 0.275042 0.275042)
							(end 0.3048 0.2032)
						)
					)
					(width 0)
					(fill yes)
				)
			)
		)
		(pad "2" smd custom
			(at 0 0.4445 180)
			(size 0.1524 0.1524)
			(layers "F.Cu" "F.Mask" "F.Paste")
			(net "GND")
			(options
				(clearance outline)
				(anchor circle)
			)
			(primitives
				(gr_poly
					(pts
						(arc
							(start 0.3048 -0.2032)
							(mid 0.275042 -0.275042)
							(end 0.2032 -0.3048)
						)
						(arc
							(start -0.2032 -0.3048)
							(mid -0.275042 -0.275042)
							(end -0.3048 -0.2032)
						)
						(arc
							(start -0.3048 0.2032)
							(mid -0.275042 0.275042)
							(end -0.2032 0.3048)
						)
						(arc
							(start 0.2032 0.3048)
							(mid 0.275042 0.275042)
							(end 0.3048 0.2032)
						)
					)
					(width 0)
					(fill yes)
				)
			)
		)
	)
	(footprint ""
		(layer "F.Cu")
		(at 23.368 -369.697 -90)
		(property "Reference" "PC4"
			(at 0 0 270)
			(layer "F.SilkS")
			(hide yes)
			(effects
				(font
					(size 1.27 1.27)
				)
			)
		)
		(property "Value" "SC1U25V3KX-1-GP"
			(at 0 -2.8194 270)
			(unlocked yes)
			(layer "F.Fab")
			(hide yes)
			(effects
				(font
					(size 1.016 1.016)
					(thickness 0.1524)
				)
			)
		)
		(property "Device Type" "C603H36"
			(at 0 -4.3434 270)
			(unlocked yes)
			(layer "F.Fab")
			(hide yes)
			(effects
				(font
					(size 1.016 1.016)
					(thickness 0.1524)
				)
			)
		)
		(duplicate_pad_numbers_are_jumpers no)
		(fp_line
			(start 0.508 0)
			(end -0.508 0)
			(stroke
				(width 0.2032)
				(type default)
			)
			(layer "F.SilkS")
		)
		(fp_rect
			(start -0.5842 1.3335)
			(end 0.5842 -1.3335)
			(stroke
				(width 0)
				(type default)
			)
			(fill no)
			(layer "F.CrtYd")
		)
		(fp_rect
			(start -0.5842 1.3335)
			(end 0.5842 -1.3335)
			(stroke
				(width 0)
				(type default)
			)
			(fill no)
			(layer "F.Fab")
		)
		(pad "1" smd custom
			(at 0 -0.762 270)
			(size 0.2159 0.2159)
			(layers "F.Cu" "F.Mask" "F.Paste")
			(net "ADM1276_VCAP")
			(options
				(clearance outline)
				(anchor circle)
			)
			(primitives
				(gr_poly
					(pts
						(arc
							(start -0.3302 -0.4318)
							(mid -0.402042 -0.402042)
							(end -0.4318 -0.3302)
						)
						(arc
							(start -0.4318 0.3302)
							(mid -0.402042 0.402042)
							(end -0.3302 0.4318)
						)
						(arc
							(start 0.3302 0.4318)
							(mid 0.402042 0.402042)
							(end 0.4318 0.3302)
						)
						(arc
							(start 0.4318 -0.3302)
							(mid 0.402042 -0.402042)
							(end 0.3302 -0.4318)
						)
					)
					(width 0)
					(fill yes)
				)
			)
		)
		(pad "2" smd custom
			(at 0 0.762 270)
			(size 0.2159 0.2159)
			(layers "F.Cu" "F.Mask" "F.Paste")
			(net "GND")
			(options
				(clearance outline)
				(anchor circle)
			)
			(primitives
				(gr_poly
					(pts
						(arc
							(start -0.3302 -0.4318)
							(mid -0.402042 -0.402042)
							(end -0.4318 -0.3302)
						)
						(arc
							(start -0.4318 0.3302)
							(mid -0.402042 0.402042)
							(end -0.3302 0.4318)
						)
						(arc
							(start 0.3302 0.4318)
							(mid 0.402042 0.402042)
							(end 0.4318 0.3302)
						)
						(arc
							(start 0.4318 -0.3302)
							(mid 0.402042 -0.402042)
							(end 0.3302 -0.4318)
						)
					)
					(width 0)
					(fill yes)
				)
			)
		)
	)
	(footprint ""
		(layer "F.Cu")
		(at 13.923518 -230.153972 180)
		(property "Reference" "Q5"
			(at 0 0 180)
			(layer "F.SilkS")
			(hide yes)
			(effects
				(font
					(size 1.27 1.27)
				)
			)
		)
		(property "Value" "PMBS3904-1-GP"
			(at 0 -9.0932 180)
			(unlocked yes)
			(layer "F.Fab")
			(hide yes)
			(effects
				(font
					(size 1.016 1.016)
					(thickness 0.1524)
				)
			)
		)
		(property "Device Type" "SOT-23-10H44"
			(at 0 -10.6172 180)
			(unlocked yes)
			(layer "F.Fab")
			(hide yes)
			(effects
				(font
					(size 1.016 1.016)
					(thickness 0.1524)
				)
			)
		)
		(duplicate_pad_numbers_are_jumpers no)
		(fp_line
			(start 1.651 1.778)
			(end 1.651 -1.778)
			(stroke
				(width 0.1524)
				(type default)
			)
			(layer "F.SilkS")
		)
		(fp_line
			(start 1.651 -1.778)
			(end -1.651 -1.778)
			(stroke
				(width 0.1524)
				(type default)
			)
			(layer "F.SilkS")
		)
		(fp_line
			(start -0.635 1.8796)
			(end -1.7526 1.8796)
			(stroke
				(width 0.3302)
				(type default)
			)
			(layer "F.SilkS")
		)
		(fp_line
			(start -0.71628 2.15265)
			(end -1.26492 2.15265)
			(stroke
				(width 0.0127)
				(type default)
			)
			(layer "F.SilkS")
		)
		(fp_line
			(start -0.719074 2.145538)
			(end -1.265936 2.14122)
			(stroke
				(width 0.0127)
				(type default)
			)
			(layer "F.SilkS")
		)
		(fp_line
			(start -0.9906 1.86309)
			(end -0.701294 2.15265)
			(stroke
				(width 0.0127)
				(type default)
			)
			(layer "F.SilkS")
		)
		(fp_line
			(start -0.994156 1.8669)
			(end -0.987044 1.8669)
			(stroke
				(width 0.0127)
				(type default)
			)
			(layer "F.SilkS")
		)
		(fp_line
			(start -1.003808 1.876552)
			(end -0.977646 1.876552)
			(stroke
				(width 0.0127)
				(type default)
			)
			(layer "F.SilkS")
		)
		(fp_line
			(start -1.013206 1.88595)
			(end -0.967994 1.88595)
			(stroke
				(width 0.0127)
				(type default)
			)
			(layer "F.SilkS")
		)
		(fp_line
			(start -1.022858 1.895602)
			(end -0.958596 1.895602)
			(stroke
				(width 0.0127)
				(type default)
			)
			(layer "F.SilkS")
		)
		(fp_line
			(start -1.032256 1.905)
			(end -0.948944 1.905)
			(stroke
				(width 0.0127)
				(type default)
			)
			(layer "F.SilkS")
		)
		(fp_line
			(start -1.041908 1.914652)
			(end -0.939546 1.914652)
			(stroke
				(width 0.0127)
				(type default)
			)
			(layer "F.SilkS")
		)
		(fp_line
			(start -1.051306 1.92405)
			(end -0.929894 1.92405)
			(stroke
				(width 0.0127)
				(type default)
			)
			(layer "F.SilkS")
		)
		(fp_line
			(start -1.060958 1.933702)
			(end -0.920496 1.933702)
			(stroke
				(width 0.0127)
				(type default)
			)
			(layer "F.SilkS")
		)
		(fp_line
			(start -1.070356 1.9431)
			(end -0.910844 1.9431)
			(stroke
				(width 0.0127)
				(type default)
			)
			(layer "F.SilkS")
		)
		(fp_line
			(start -1.080008 1.952752)
			(end -0.901446 1.952752)
			(stroke
				(width 0.0127)
				(type default)
			)
			(layer "F.SilkS")
		)
		(fp_line
			(start -1.089406 1.96215)
			(end -0.891794 1.96215)
			(stroke
				(width 0.0127)
				(type default)
			)
			(layer "F.SilkS")
		)
		(fp_line
			(start -1.099058 1.971802)
			(end -0.882396 1.971802)
			(stroke
				(width 0.0127)
				(type default)
			)
			(layer "F.SilkS")
		)
		(fp_line
			(start -1.108456 1.9812)
			(end -0.872744 1.9812)
			(stroke
				(width 0.0127)
				(type default)
			)
			(layer "F.SilkS")
		)
		(fp_line
			(start -1.118108 1.990852)
			(end -0.863346 1.990852)
			(stroke
				(width 0.0127)
				(type default)
			)
			(layer "F.SilkS")
		)
		(fp_line
			(start -1.127506 2.00025)
			(end -0.853694 2.00025)
			(stroke
				(width 0.0127)
				(type default)
			)
			(layer "F.SilkS")
		)
		(fp_line
			(start -1.137158 2.009902)
			(end -0.844296 2.009902)
			(stroke
				(width 0.0127)
				(type default)
			)
			(layer "F.SilkS")
		)
		(fp_line
			(start -1.146556 2.0193)
			(end -0.834644 2.0193)
			(stroke
				(width 0.0127)
				(type default)
			)
			(layer "F.SilkS")
		)
		(fp_line
			(start -1.156208 2.028952)
			(end -0.825246 2.028952)
			(stroke
				(width 0.0127)
				(type default)
			)
			(layer "F.SilkS")
		)
		(fp_line
			(start -1.165606 2.03835)
			(end -0.815594 2.03835)
			(stroke
				(width 0.0127)
				(type default)
			)
			(layer "F.SilkS")
		)
		(fp_line
			(start -1.175258 2.048002)
			(end -0.806196 2.048002)
			(stroke
				(width 0.0127)
				(type default)
			)
			(layer "F.SilkS")
		)
		(fp_line
			(start -1.184656 2.0574)
			(end -0.796544 2.0574)
			(stroke
				(width 0.0127)
				(type default)
			)
			(layer "F.SilkS")
		)
		(fp_line
			(start -1.194308 2.067052)
			(end -0.787146 2.067052)
			(stroke
				(width 0.0127)
				(type default)
			)
			(layer "F.SilkS")
		)
		(fp_line
			(start -1.203706 2.07645)
			(end -0.777494 2.07645)
			(stroke
				(width 0.0127)
				(type default)
			)
			(layer "F.SilkS")
		)
		(fp_line
			(start -1.213358 2.086102)
			(end -0.768096 2.086102)
			(stroke
				(width 0.0127)
				(type default)
			)
			(layer "F.SilkS")
		)
		(fp_line
			(start -1.222756 2.0955)
			(end -0.758444 2.0955)
			(stroke
				(width 0.0127)
				(type default)
			)
			(layer "F.SilkS")
		)
		(fp_line
			(start -1.232408 2.105152)
			(end -0.749046 2.105152)
			(stroke
				(width 0.0127)
				(type default)
			)
			(layer "F.SilkS")
		)
		(fp_line
			(start -1.241806 2.11455)
			(end -0.739394 2.11455)
			(stroke
				(width 0.0127)
				(type default)
			)
			(layer "F.SilkS")
		)
		(fp_line
			(start -1.251458 2.124202)
			(end -0.729996 2.124202)
			(stroke
				(width 0.0127)
				(type default)
			)
			(layer "F.SilkS")
		)
		(fp_line
			(start -1.260856 2.1336)
			(end -0.720344 2.1336)
			(stroke
				(width 0.0127)
				(type default)
			)
			(layer "F.SilkS")
		)
		(fp_line
			(start -1.279144 2.15265)
			(end -0.701294 2.15265)
			(stroke
				(width 0.0127)
				(type default)
			)
			(layer "F.SilkS")
		)
		(fp_line
			(start -1.279398 2.152142)
			(end -0.9906 1.86309)
			(stroke
				(width 0.0127)
				(type default)
			)
			(layer "F.SilkS")
		)
		(fp_line
			(start -1.651 1.778)
			(end 1.651 1.778)
			(stroke
				(width 0.1524)
				(type default)
			)
			(layer "F.SilkS")
		)
		(fp_line
			(start -1.651 -1.778)
			(end -1.651 1.778)
			(stroke
				(width 0.1524)
				(type default)
			)
			(layer "F.SilkS")
		)
		(fp_line
			(start -1.7526 1.8796)
			(end -1.7526 0.9906)
			(stroke
				(width 0.3302)
				(type default)
			)
			(layer "F.SilkS")
		)
		(fp_poly
			(pts
				(xy -1.285748 2.159) (xy -1.285748 1.8796) (xy -1.778 1.8796) (xy -1.778 -1.8796) (xy 1.778 -1.8796)
				(xy 1.778 1.8796) (xy -0.694944 1.8796) (xy -0.694944 2.159)
			)
			(stroke
				(width 0)
				(type default)
			)
			(fill no)
			(layer "F.CrtYd")
		)
		(fp_poly
			(pts
				(xy -1.285748 2.159) (xy -1.285748 1.8796) (xy -1.778 1.8796) (xy -1.778 -1.8796) (xy 1.778 -1.8796)
				(xy 1.778 1.8796) (xy -0.694944 1.8796) (xy -0.694944 2.159)
			)
			(stroke
				(width 0)
				(type default)
			)
			(fill no)
			(layer "F.Fab")
		)
		(pad "1" smd rect
			(at -0.98425 0.9525 180)
			(size 0.762 1.143)
			(layers "F.Cu" "F.Mask" "F.Paste")
			(net "LED_DR_LED3_B")
		)
		(pad "2" smd rect
			(at 0.98425 0.9525 180)
			(size 0.762 1.143)
			(layers "F.Cu" "F.Mask" "F.Paste")
			(net "GND")
		)
		(pad "3" smd rect
			(at 0 -0.9525 180)
			(size 0.762 1.143)
			(layers "F.Cu" "F.Mask" "F.Paste")
			(net "LED_DR_LED3_BLUE")
		)
	)
	(footprint ""
		(layer "F.Cu")
		(at 43.3324 -134.8232)
		(property "Reference" "PR96"
			(at 0 0 0)
			(layer "F.SilkS")
			(hide yes)
			(effects
				(font
					(size 1.27 1.27)
				)
			)
		)
		(property "Value" "0R2J-2-GP"
			(at 0.064008 -3.993896 0)
			(unlocked yes)
			(layer "F.Fab")
			(hide yes)
			(effects
				(font
					(size 1.016 1.016)
					(thickness 0.1524)
				)
			)
		)
		(property "Device Type" "R402H16"
			(at 0.064008 -5.517896 0)
			(unlocked yes)
			(layer "F.Fab")
			(hide yes)
			(effects
				(font
					(size 1.016 1.016)
					(thickness 0.1524)
				)
			)
		)
		(duplicate_pad_numbers_are_jumpers no)
		(fp_line
			(start -0.508 -0.9398)
			(end -0.508 0.9398)
			(stroke
				(width 0.1524)
				(type default)
			)
			(layer "F.SilkS")
		)
		(fp_line
			(start 0.508 -0.9398)
			(end -0.508 -0.9398)
			(stroke
				(width 0.1524)
				(type default)
			)
			(layer "F.SilkS")
		)
		(fp_rect
			(start -0.508 0.9398)
			(end 0.508 -0.9398)
			(stroke
				(width 0)
				(type default)
			)
			(fill no)
			(layer "F.CrtYd")
		)
		(fp_rect
			(start -0.508 0.9398)
			(end 0.508 -0.9398)
			(stroke
				(width 0)
				(type default)
			)
			(fill no)
			(layer "F.Fab")
		)
		(pad "1" smd custom
			(at 0 -0.4445)
			(size 0.1397 0.1397)
			(layers "F.Cu" "F.Mask" "F.Paste")
			(net "P12VL_2490_VCC")
			(options
				(clearance outline)
				(anchor circle)
			)
			(primitives
				(gr_poly
					(pts
						(arc
							(start -0.1778 -0.2794)
							(mid -0.249642 -0.249642)
							(end -0.2794 -0.1778)
						)
						(arc
							(start -0.2794 0.1778)
							(mid -0.249642 0.249642)
							(end -0.1778 0.2794)
						)
						(arc
							(start 0.1778 0.2794)
							(mid 0.249642 0.249642)
							(end 0.2794 0.1778)
						)
						(arc
							(start 0.2794 -0.1778)
							(mid 0.249642 -0.249642)
							(end 0.1778 -0.2794)
						)
					)
					(width 0)
					(fill yes)
				)
			)
		)
		(pad "2" smd custom
			(at 0 0.4445)
			(size 0.1397 0.1397)
			(layers "F.Cu" "F.Mask" "F.Paste")
			(net "P12V")
			(options
				(clearance outline)
				(anchor circle)
			)
			(primitives
				(gr_poly
					(pts
						(arc
							(start -0.1778 -0.2794)
							(mid -0.249642 -0.249642)
							(end -0.2794 -0.1778)
						)
						(arc
							(start -0.2794 0.1778)
							(mid -0.249642 0.249642)
							(end -0.1778 0.2794)
						)
						(arc
							(start 0.1778 0.2794)
							(mid 0.249642 0.249642)
							(end 0.2794 0.1778)
						)
						(arc
							(start 0.2794 -0.1778)
							(mid 0.249642 -0.249642)
							(end 0.1778 -0.2794)
						)
					)
					(width 0)
					(fill yes)
				)
			)
		)
	)
	(footprint ""
		(layer "F.Cu")
		(at 46.863 -416.814 90)
		(property "Reference" "PC8"
			(at 0 0 90)
			(layer "F.SilkS")
			(hide yes)
			(effects
				(font
					(size 1.27 1.27)
				)
			)
		)
		(property "Value" "SC1U25V5KX-1GP"
			(at -0.0762 -6.1214 90)
			(unlocked yes)
			(layer "F.Fab")
			(hide yes)
			(effects
				(font
					(size 1.016 1.016)
					(thickness 0.1524)
				)
			)
		)
		(property "Device Type" "C805H58"
			(at -0.0762 -8.1534 90)
			(unlocked yes)
			(layer "F.Fab")
			(hide yes)
			(effects
				(font
					(size 1.016 1.016)
					(thickness 0.1524)
				)
			)
		)
		(duplicate_pad_numbers_are_jumpers no)
		(fp_line
			(start 0.635 0)
			(end -0.635 0)
			(stroke
				(width 0.508)
				(type default)
			)
			(layer "F.SilkS")
		)
		(fp_rect
			(start -0.9652 1.778)
			(end 0.9652 -1.778)
			(stroke
				(width 0)
				(type default)
			)
			(fill no)
			(layer "F.CrtYd")
		)
		(fp_poly
			(pts
				(xy -0.9652 -1.778) (xy 0.9652 -1.778) (xy 0.9652 1.778) (xy -0.9652 1.778)
			)
			(stroke
				(width 0)
				(type default)
			)
			(fill no)
			(layer "F.Fab")
		)
		(pad "1" smd rect
			(at 0 -0.9652 90)
			(size 1.397 1.143)
			(layers "F.Cu" "F.Mask" "F.Paste")
			(net "P12V_AUX")
		)
		(pad "2" smd rect
			(at 0 0.9652 90)
			(size 1.397 1.143)
			(layers "F.Cu" "F.Mask" "F.Paste")
			(net "GND")
		)
	)
)
